(kicad_pcb
	(version 20260206)
	(generator "pcbnew")
	(generator_version "10.0")
	(general
		(thickness 1.6)
		(legacy_teardrops no)
	)
	(paper "A4")
	(title_block
		(title "Bryce Canyon_SCC_16316-1_OCP.brd")
		(comment 1 "Bryce Canyon / footprints 1528-1535 of 1561")
	)
	(layers
		(0 "F.Cu" signal "TOP")
		(4 "In1.Cu" signal "L2GND")
		(6 "In2.Cu" signal "L3")
		(8 "In3.Cu" signal "L4VCC")
		(10 "In4.Cu" signal "L5VCC")
		(12 "In5.Cu" signal "L6")
		(14 "In6.Cu" signal "L7GND")
		(2 "B.Cu" signal "BOTTOM")
		(9 "F.Adhes" user "F.Adhesive")
		(11 "B.Adhes" user "B.Adhesive")
		(13 "F.Paste" user "Package Geometry/Pastemask Top")
		(15 "B.Paste" user "Package Geometry/Pastemask Bottom")
		(5 "F.SilkS" user "Ref Des/Silkscreen Top")
		(7 "B.SilkS" user "Ref Des/Silkscreen Bottom")
		(1 "F.Mask" user "Board Geometry/Soldermask Top")
		(3 "B.Mask" user "Board Geometry/Soldermask Bottom")
		(17 "Dwgs.User" user "User.Drawings")
		(19 "Cmts.User" user "User.Comments")
		(21 "Eco1.User" user "User.Eco1")
		(23 "Eco2.User" user "User.Eco2")
		(25 "Edge.Cuts" user "Board Geometry/Outline")
		(27 "Margin" user)
		(31 "F.CrtYd" user "Package Geometry/Place Bound Top")
		(29 "B.CrtYd" user "Package Geometry/Place Bound Bottom")
		(35 "F.Fab" user "Ref Des/Assembly Top")
		(33 "B.Fab" user "Ref Des/Assembly Bottom")
	)
	(footprint ""
		(layer "B.Cu")
		(at 175.043846 -20.954492)
		(property "Reference" "C321"
			(at 0 0 0)
			(layer "B.SilkS")
			(hide yes)
			(effects
				(font
					(size 1.27 1.27)
				)
				(justify mirror)
			)
		)
		(property "Value" "SCD22U10V1KX-GP"
			(at 2.8321 -1.7399 0)
			(unlocked yes)
			(layer "B.Fab")
			(hide yes)
			(effects
				(font
					(size 1.016 1.016)
					(thickness 0.1524)
				)
				(justify mirror)
			)
		)
		(property "Device Type" "C0201H13"
			(at 2.8321 -3.2639 0)
			(unlocked yes)
			(layer "B.Fab")
			(hide yes)
			(effects
				(font
					(size 1.016 1.016)
					(thickness 0.1524)
				)
				(justify mirror)
			)
		)
		(duplicate_pad_numbers_are_jumpers no)
		(fp_rect
			(start 0.2794 0.6477)
			(end -0.2794 -0.6477)
			(stroke
				(width 0)
				(type default)
			)
			(fill no)
			(layer "B.CrtYd")
		)
		(fp_rect
			(start 0.2794 0.6477)
			(end -0.2794 -0.6477)
			(stroke
				(width 0)
				(type default)
			)
			(fill no)
			(layer "B.Fab")
		)
		(pad "1" smd custom
			(at 0 -0.2794 180)
			(size 0.0762 0.0762)
			(layers "B.Cu" "B.Mask" "B.Paste")
			(net "PCIE_SCC_TO_COMP_C_5_DP")
			(options
				(clearance outline)
				(anchor circle)
			)
			(primitives
				(gr_poly
					(pts
						(arc
							(start 0.1524 0.127)
							(mid 0.137521 0.162921)
							(end 0.1016 0.1778)
						)
						(arc
							(start -0.1016 0.1778)
							(mid -0.137521 0.162921)
							(end -0.1524 0.127)
						)
						(arc
							(start -0.1524 -0.127)
							(mid -0.137521 -0.162921)
							(end -0.1016 -0.1778)
						)
						(arc
							(start 0.1016 -0.1778)
							(mid 0.137521 -0.162921)
							(end 0.1524 -0.127)
						)
					)
					(width 0)
					(fill yes)
				)
			)
		)
		(pad "2" smd custom
			(at 0 0.2794 180)
			(size 0.0762 0.0762)
			(layers "B.Cu" "B.Mask" "B.Paste")
			(net "PCIE_SCC_TO_COMP_5_DP")
			(options
				(clearance outline)
				(anchor circle)
			)
			(primitives
				(gr_poly
					(pts
						(arc
							(start 0.1524 0.127)
							(mid 0.137521 0.162921)
							(end 0.1016 0.1778)
						)
						(arc
							(start -0.1016 0.1778)
							(mid -0.137521 0.162921)
							(end -0.1524 0.127)
						)
						(arc
							(start -0.1524 -0.127)
							(mid -0.137521 -0.162921)
							(end -0.1016 -0.1778)
						)
						(arc
							(start 0.1016 -0.1778)
							(mid 0.137521 -0.162921)
							(end 0.1524 -0.127)
						)
					)
					(width 0)
					(fill yes)
				)
			)
		)
	)
	(footprint ""
		(layer "B.Cu")
		(at 141.224 -117.16004 -90)
		(property "Reference" "C721"
			(at 0 0 90)
			(layer "B.SilkS")
			(hide yes)
			(effects
				(font
					(size 1.27 1.27)
				)
				(justify mirror)
			)
		)
		(property "Value" "SCD1U16V2KX-3GP"
			(at -1.1811 -2.7051 270)
			(unlocked yes)
			(layer "B.Fab")
			(hide yes)
			(effects
				(font
					(size 1.016 1.016)
					(thickness 0.1524)
				)
				(justify mirror)
			)
		)
		(property "Device Type" "C402H22"
			(at -1.1811 -4.2291 270)
			(unlocked yes)
			(layer "B.Fab")
			(hide yes)
			(effects
				(font
					(size 1.016 1.016)
					(thickness 0.1524)
				)
				(justify mirror)
			)
		)
		(duplicate_pad_numbers_are_jumpers no)
		(fp_rect
			(start 0.4318 0.9525)
			(end -0.4318 -0.9525)
			(stroke
				(width 0)
				(type default)
			)
			(fill no)
			(layer "B.CrtYd")
		)
		(fp_rect
			(start 0.4318 0.9525)
			(end -0.4318 -0.9525)
			(stroke
				(width 0)
				(type default)
			)
			(fill no)
			(layer "B.Fab")
		)
		(pad "1" smd custom
			(at 0 -0.4445 90)
			(size 0.1524 0.1524)
			(layers "B.Cu" "B.Mask" "B.Paste")
			(net "P1V5_C_S")
			(options
				(clearance outline)
				(anchor circle)
			)
			(primitives
				(gr_poly
					(pts
						(arc
							(start 0.3048 0.2032)
							(mid 0.275042 0.275042)
							(end 0.2032 0.3048)
						)
						(arc
							(start -0.2032 0.3048)
							(mid -0.275042 0.275042)
							(end -0.3048 0.2032)
						)
						(arc
							(start -0.3048 -0.2032)
							(mid -0.275042 -0.275042)
							(end -0.2032 -0.3048)
						)
						(arc
							(start 0.2032 -0.3048)
							(mid 0.275042 -0.275042)
							(end 0.3048 -0.2032)
						)
					)
					(width 0)
					(fill yes)
				)
			)
		)
		(pad "2" smd custom
			(at 0 0.4445 90)
			(size 0.1524 0.1524)
			(layers "B.Cu" "B.Mask" "B.Paste")
			(net "GND")
			(options
				(clearance outline)
				(anchor circle)
			)
			(primitives
				(gr_poly
					(pts
						(arc
							(start 0.3048 0.2032)
							(mid 0.275042 0.275042)
							(end 0.2032 0.3048)
						)
						(arc
							(start -0.2032 0.3048)
							(mid -0.275042 0.275042)
							(end -0.3048 0.2032)
						)
						(arc
							(start -0.3048 -0.2032)
							(mid -0.275042 -0.275042)
							(end -0.2032 -0.3048)
						)
						(arc
							(start 0.2032 -0.3048)
							(mid 0.275042 -0.275042)
							(end 0.3048 -0.2032)
						)
					)
					(width 0)
					(fill yes)
				)
			)
		)
	)
	(footprint ""
		(layer "B.Cu")
		(at 188.716412 -52.375308 -90)
		(property "Reference" "TP104"
			(at 0 0 90)
			(layer "B.SilkS")
			(hide yes)
			(effects
				(font
					(size 1.27 1.27)
				)
				(justify mirror)
			)
		)
		(property "Value" "TPAD28-2-GP"
			(at 0.0127 -1.6637 270)
			(unlocked yes)
			(layer "B.Fab")
			(hide yes)
			(effects
				(font
					(size 1.016 1.016)
					(thickness 0.1524)
				)
				(justify mirror)
			)
		)
		(property "Device Type" "TPAD28"
			(at 0.0127 -3.1877 270)
			(unlocked yes)
			(layer "B.Fab")
			(hide yes)
			(effects
				(font
					(size 1.016 1.016)
					(thickness 0.1524)
				)
				(justify mirror)
			)
		)
		(duplicate_pad_numbers_are_jumpers no)
		(fp_poly
			(pts
				(arc
					(start 0 -0.3556)
					(mid 0 0.3556)
					(end 0 -0.3556)
				)
			)
			(stroke
				(width 0)
				(type default)
			)
			(fill no)
			(layer "B.CrtYd")
		)
		(fp_poly
			(pts
				(arc
					(start 0 -0.6096)
					(mid 0 0.6096)
					(end 0 -0.6096)
				)
			)
			(stroke
				(width 0)
				(type default)
			)
			(fill no)
			(layer "B.Fab")
		)
		(pad "1" smd circle
			(at 0 0 90)
			(size 0.7112 0.7112)
			(layers "B.Cu" "B.Mask" "B.Paste")
			(net "XM_ADDR_17")
		)
	)
	(footprint ""
		(layer "B.Cu")
		(at 73.66 -62.23 180)
		(property "Reference" "C234"
			(at 0 0 0)
			(layer "B.SilkS")
			(hide yes)
			(effects
				(font
					(size 1.27 1.27)
				)
				(justify mirror)
			)
		)
		(property "Value" "SC100U6D3V6MX-GP"
			(at 0.0762 -5.1308 180)
			(unlocked yes)
			(layer "B.Fab")
			(hide yes)
			(effects
				(font
					(size 1.016 1.016)
					(thickness 0.1524)
				)
				(justify mirror)
			)
		)
		(property "Device Type" "C1206H71"
			(at 0.127 -6.6548 180)
			(unlocked yes)
			(layer "B.Fab")
			(hide yes)
			(effects
				(font
					(size 1.016 1.016)
					(thickness 0.1524)
				)
				(justify mirror)
			)
		)
		(duplicate_pad_numbers_are_jumpers no)
		(fp_line
			(start 1.016 2.2352)
			(end 1.016 0.8382)
			(stroke
				(width 0.1524)
				(type default)
			)
			(layer "B.SilkS")
		)
		(fp_line
			(start 1.016 -0.8382)
			(end 1.016 -2.2352)
			(stroke
				(width 0.1524)
				(type default)
			)
			(layer "B.SilkS")
		)
		(fp_line
			(start 1.016 -2.2352)
			(end -1.016 -2.2352)
			(stroke
				(width 0.1524)
				(type default)
			)
			(layer "B.SilkS")
		)
		(fp_line
			(start -1.016 2.2352)
			(end 1.016 2.2352)
			(stroke
				(width 0.1524)
				(type default)
			)
			(layer "B.SilkS")
		)
		(fp_line
			(start -1.016 0.8382)
			(end -1.016 2.2352)
			(stroke
				(width 0.1524)
				(type default)
			)
			(layer "B.SilkS")
		)
		(fp_line
			(start -1.016 -2.2352)
			(end -1.016 -0.8382)
			(stroke
				(width 0.1524)
				(type default)
			)
			(layer "B.SilkS")
		)
		(fp_rect
			(start 1.0922 2.3114)
			(end -1.0922 -2.3114)
			(stroke
				(width 0)
				(type default)
			)
			(fill no)
			(layer "B.CrtYd")
		)
		(fp_poly
			(pts
				(xy -1.0922 -2.3114) (xy -1.0922 2.3114) (xy 1.0922 2.3114) (xy 1.0922 -2.3114)
			)
			(stroke
				(width 0)
				(type default)
			)
			(fill no)
			(layer "B.Fab")
		)
		(pad "1" smd rect
			(at 0 -1.397)
			(size 1.651 1.27)
			(layers "B.Cu" "B.Mask" "B.Paste")
			(net "GB_VDDA")
		)
		(pad "2" smd rect
			(at 0 1.397)
			(size 1.651 1.27)
			(layers "B.Cu" "B.Mask" "B.Paste")
			(net "GND")
		)
	)
	(footprint ""
		(layer "B.Cu")
		(at 136.2456 -81.1276 -90)
		(property "Reference" "C2"
			(at 0 0 90)
			(layer "B.SilkS")
			(hide yes)
			(effects
				(font
					(size 1.27 1.27)
				)
				(justify mirror)
			)
		)
		(property "Value" "SCD01U16V1KX-GP"
			(at 2.8321 -1.7399 270)
			(unlocked yes)
			(layer "B.Fab")
			(hide yes)
			(effects
				(font
					(size 1.016 1.016)
					(thickness 0.1524)
				)
				(justify mirror)
			)
		)
		(property "Device Type" "C0201H13"
			(at 2.8321 -3.2639 270)
			(unlocked yes)
			(layer "B.Fab")
			(hide yes)
			(effects
				(font
					(size 1.016 1.016)
					(thickness 0.1524)
				)
				(justify mirror)
			)
		)
		(duplicate_pad_numbers_are_jumpers no)
		(fp_rect
			(start 0.2794 0.6477)
			(end -0.2794 -0.6477)
			(stroke
				(width 0)
				(type default)
			)
			(fill no)
			(layer "B.CrtYd")
		)
		(fp_rect
			(start 0.2794 0.6477)
			(end -0.2794 -0.6477)
			(stroke
				(width 0)
				(type default)
			)
			(fill no)
			(layer "B.Fab")
		)
		(pad "1" smd custom
			(at 0 -0.2794 90)
			(size 0.0762 0.0762)
			(layers "B.Cu" "B.Mask" "B.Paste")
			(net "PHY_CONN_TO_EXP_11_DN")
			(options
				(clearance outline)
				(anchor circle)
			)
			(primitives
				(gr_poly
					(pts
						(arc
							(start 0.1524 0.127)
							(mid 0.137521 0.162921)
							(end 0.1016 0.1778)
						)
						(arc
							(start -0.1016 0.1778)
							(mid -0.137521 0.162921)
							(end -0.1524 0.127)
						)
						(arc
							(start -0.1524 -0.127)
							(mid -0.137521 -0.162921)
							(end -0.1016 -0.1778)
						)
						(arc
							(start 0.1016 -0.1778)
							(mid 0.137521 -0.162921)
							(end 0.1524 -0.127)
						)
					)
					(width 0)
					(fill yes)
				)
			)
		)
		(pad "2" smd custom
			(at 0 0.2794 90)
			(size 0.0762 0.0762)
			(layers "B.Cu" "B.Mask" "B.Paste")
			(net "PHY_CONN_TO_EXP_C_11_DN")
			(options
				(clearance outline)
				(anchor circle)
			)
			(primitives
				(gr_poly
					(pts
						(arc
							(start 0.1524 0.127)
							(mid 0.137521 0.162921)
							(end 0.1016 0.1778)
						)
						(arc
							(start -0.1016 0.1778)
							(mid -0.137521 0.162921)
							(end -0.1524 0.127)
						)
						(arc
							(start -0.1524 -0.127)
							(mid -0.137521 -0.162921)
							(end -0.1016 -0.1778)
						)
						(arc
							(start 0.1016 -0.1778)
							(mid 0.137521 -0.162921)
							(end 0.1524 -0.127)
						)
					)
					(width 0)
					(fill yes)
				)
			)
		)
	)
	(footprint ""
		(layer "B.Cu")
		(at 115.3033 -64.4779)
		(property "Reference" "C164"
			(at 0 0 0)
			(layer "B.SilkS")
			(hide yes)
			(effects
				(font
					(size 1.27 1.27)
				)
				(justify mirror)
			)
		)
		(property "Value" "SCD1U6D3V1KX-GP"
			(at 2.8321 -1.7399 0)
			(unlocked yes)
			(layer "B.Fab")
			(hide yes)
			(effects
				(font
					(size 1.016 1.016)
					(thickness 0.1524)
				)
				(justify mirror)
			)
		)
		(property "Device Type" "C0201H13"
			(at 2.8321 -3.2639 0)
			(unlocked yes)
			(layer "B.Fab")
			(hide yes)
			(effects
				(font
					(size 1.016 1.016)
					(thickness 0.1524)
				)
				(justify mirror)
			)
		)
		(duplicate_pad_numbers_are_jumpers no)
		(fp_rect
			(start 0.2794 0.6477)
			(end -0.2794 -0.6477)
			(stroke
				(width 0)
				(type default)
			)
			(fill no)
			(layer "B.CrtYd")
		)
		(fp_rect
			(start 0.2794 0.6477)
			(end -0.2794 -0.6477)
			(stroke
				(width 0)
				(type default)
			)
			(fill no)
			(layer "B.Fab")
		)
		(pad "1" smd custom
			(at 0 -0.2794 180)
			(size 0.0762 0.0762)
			(layers "B.Cu" "B.Mask" "B.Paste")
			(net "P0V9")
			(options
				(clearance outline)
				(anchor circle)
			)
			(primitives
				(gr_poly
					(pts
						(arc
							(start 0.1524 0.127)
							(mid 0.137521 0.162921)
							(end 0.1016 0.1778)
						)
						(arc
							(start -0.1016 0.1778)
							(mid -0.137521 0.162921)
							(end -0.1524 0.127)
						)
						(arc
							(start -0.1524 -0.127)
							(mid -0.137521 -0.162921)
							(end -0.1016 -0.1778)
						)
						(arc
							(start 0.1016 -0.1778)
							(mid 0.137521 -0.162921)
							(end 0.1524 -0.127)
						)
					)
					(width 0)
					(fill yes)
				)
			)
		)
		(pad "2" smd custom
			(at 0 0.2794 180)
			(size 0.0762 0.0762)
			(layers "B.Cu" "B.Mask" "B.Paste")
			(net "GND")
			(options
				(clearance outline)
				(anchor circle)
			)
			(primitives
				(gr_poly
					(pts
						(arc
							(start 0.1524 0.127)
							(mid 0.137521 0.162921)
							(end 0.1016 0.1778)
						)
						(arc
							(start -0.1016 0.1778)
							(mid -0.137521 0.162921)
							(end -0.1524 0.127)
						)
						(arc
							(start -0.1524 -0.127)
							(mid -0.137521 -0.162921)
							(end -0.1016 -0.1778)
						)
						(arc
							(start 0.1016 -0.1778)
							(mid 0.137521 -0.162921)
							(end 0.1524 -0.127)
						)
					)
					(width 0)
					(fill yes)
				)
			)
		)
	)
	(footprint ""
		(layer "B.Cu")
		(at 118.872 -86.995 180)
		(property "Reference" "R210"
			(at 0 0 0)
			(layer "B.SilkS")
			(hide yes)
			(effects
				(font
					(size 1.27 1.27)
				)
				(justify mirror)
			)
		)
		(property "Value" "0R2J-2-GP"
			(at -0.064008 -3.993896 180)
			(unlocked yes)
			(layer "B.Fab")
			(hide yes)
			(effects
				(font
					(size 1.016 1.016)
					(thickness 0.1524)
				)
				(justify mirror)
			)
		)
		(property "Device Type" "R402H16"
			(at -0.064008 -5.517896 180)
			(unlocked yes)
			(layer "B.Fab")
			(hide yes)
			(effects
				(font
					(size 1.016 1.016)
					(thickness 0.1524)
				)
				(justify mirror)
			)
		)
		(duplicate_pad_numbers_are_jumpers no)
		(fp_line
			(start 0.508 -0.9398)
			(end 0.508 0.9398)
			(stroke
				(width 0.1524)
				(type default)
			)
			(layer "B.SilkS")
		)
		(fp_line
			(start -0.508 -0.9398)
			(end 0.508 -0.9398)
			(stroke
				(width 0.1524)
				(type default)
			)
			(layer "B.SilkS")
		)
		(fp_rect
			(start 0.508 0.9398)
			(end -0.508 -0.9398)
			(stroke
				(width 0)
				(type default)
			)
			(fill no)
			(layer "B.CrtYd")
		)
		(fp_rect
			(start 0.508 0.9398)
			(end -0.508 -0.9398)
			(stroke
				(width 0)
				(type default)
			)
			(fill no)
			(layer "B.Fab")
		)
		(pad "1" smd custom
			(at 0 -0.4445)
			(size 0.1397 0.1397)
			(layers "B.Cu" "B.Mask" "B.Paste")
			(net "COMP_EXP_SPARE_1_R_LS")
			(options
				(clearance outline)
				(anchor circle)
			)
			(primitives
				(gr_poly
					(pts
						(arc
							(start -0.1778 0.2794)
							(mid -0.249642 0.249642)
							(end -0.2794 0.1778)
						)
						(arc
							(start -0.2794 -0.1778)
							(mid -0.249642 -0.249642)
							(end -0.1778 -0.2794)
						)
						(arc
							(start 0.1778 -0.2794)
							(mid 0.249642 -0.249642)
							(end 0.2794 -0.1778)
						)
						(arc
							(start 0.2794 0.1778)
							(mid 0.249642 0.249642)
							(end 0.1778 0.2794)
						)
					)
					(width 0)
					(fill yes)
				)
			)
		)
		(pad "2" smd custom
			(at 0 0.4445)
			(size 0.1397 0.1397)
			(layers "B.Cu" "B.Mask" "B.Paste")
			(net "COMP_SPARE_0_LS")
			(options
				(clearance outline)
				(anchor circle)
			)
			(primitives
				(gr_poly
					(pts
						(arc
							(start -0.1778 0.2794)
							(mid -0.249642 0.249642)
							(end -0.2794 0.1778)
						)
						(arc
							(start -0.2794 -0.1778)
							(mid -0.249642 -0.249642)
							(end -0.1778 -0.2794)
						)
						(arc
							(start 0.1778 -0.2794)
							(mid 0.249642 -0.249642)
							(end 0.2794 -0.1778)
						)
						(arc
							(start 0.2794 0.1778)
							(mid 0.249642 0.249642)
							(end 0.1778 0.2794)
						)
					)
					(width 0)
					(fill yes)
				)
			)
		)
	)
	(footprint ""
		(layer "B.Cu")
		(at 89.464388 -74.610214 180)
		(property "Reference" "L4"
			(at 0 0 0)
			(layer "B.SilkS")
			(hide yes)
			(effects
				(font
					(size 1.27 1.27)
				)
				(justify mirror)
			)
		)
		(property "Value" "MPZ2012S601AT-GP"
			(at 0 -4.2418 180)
			(unlocked yes)
			(layer "B.Fab")
			(hide yes)
			(effects
				(font
					(size 1.016 1.016)
					(thickness 0.1524)
				)
				(justify mirror)
			)
		)
		(property "Device Type" "L805H42"
			(at 0 -5.7912 180)
			(unlocked yes)
			(layer "B.Fab")
			(hide yes)
			(effects
				(font
					(size 1.016 1.016)
					(thickness 0.1524)
				)
				(justify mirror)
			)
		)
		(duplicate_pad_numbers_are_jumpers no)
		(fp_line
			(start 0.889 1.7018)
			(end 0.889 -1.7018)
			(stroke
				(width 0.1524)
				(type default)
			)
			(layer "B.SilkS")
		)
		(fp_line
			(start 0.889 -1.7018)
			(end -0.889 -1.7018)
			(stroke
				(width 0.1524)
				(type default)
			)
			(layer "B.SilkS")
		)
		(fp_line
			(start -0.889 1.7018)
			(end 0.889 1.7018)
			(stroke
				(width 0.1524)
				(type default)
			)
			(layer "B.SilkS")
		)
		(fp_line
			(start -0.889 -1.7018)
			(end -0.889 1.7018)
			(stroke
				(width 0.1524)
				(type default)
			)
			(layer "B.SilkS")
		)
		(fp_rect
			(start 0.9652 1.778)
			(end -0.9652 -1.778)
			(stroke
				(width 0)
				(type default)
			)
			(fill no)
			(layer "B.CrtYd")
		)
		(fp_rect
			(start 0.9652 1.778)
			(end -0.9652 -1.778)
			(stroke
				(width 0)
				(type default)
			)
			(fill no)
			(layer "B.Fab")
		)
		(pad "1" smd rect
			(at 0 -0.9652)
			(size 1.397 1.143)
			(layers "B.Cu" "B.Mask" "B.Paste")
			(net "XTAL_VDDA09")
		)
		(pad "2" smd rect
			(at 0 0.9652)
			(size 1.397 1.143)
			(layers "B.Cu" "B.Mask" "B.Paste")
			(net "P0V9")
		)
	)
)
